(kicad_pcb
	(version 20260206)
	(generator "pcbnew")
	(generator_version "10.0")
	(general
		(thickness 1.6)
		(legacy_teardrops no)
	)
	(paper "A4")
	(title_block
		(title "Wiwynn_Tioga_Pass_MB.brd")
		(comment 1 "Tioga Pass / footprint 2254 of 4770 (U5D1), pads 2980-3046 of 3647")
	)
	(layers
		(0 "F.Cu" signal "TOP")
		(4 "In1.Cu" signal "L2GND")
		(6 "In2.Cu" signal "L3")
		(8 "In3.Cu" signal "L4GND")
		(10 "In4.Cu" signal "L5")
		(12 "In5.Cu" signal "L6GND")
		(14 "In6.Cu" signal "L7VCC")
		(16 "In7.Cu" signal "L8VCC")
		(18 "In8.Cu" signal "L9GND")
		(20 "In9.Cu" signal "L10")
		(22 "In10.Cu" signal "L11GND")
		(24 "In11.Cu" signal "L12")
		(26 "In12.Cu" signal "L13GND")
		(2 "B.Cu" signal "BOTTOM")
		(9 "F.Adhes" user "F.Adhesive")
		(11 "B.Adhes" user "B.Adhesive")
		(13 "F.Paste" user "Package Geometry/Pastemask Top")
		(15 "B.Paste" user "Package Geometry/Pastemask Bottom")
		(5 "F.SilkS" user "Ref Des/Silkscreen Top")
		(7 "B.SilkS" user "Ref Des/Silkscreen Bottom")
		(1 "F.Mask" user "Board Geometry/Soldermask Top")
		(3 "B.Mask" user "Board Geometry/Soldermask Bottom")
		(17 "Dwgs.User" user "User.Drawings")
		(19 "Cmts.User" user "User.Comments")
		(21 "Eco1.User" user "User.Eco1")
		(23 "Eco2.User" user "User.Eco2")
		(25 "Edge.Cuts" user "Board Geometry/Outline")
		(27 "Margin" user)
		(31 "F.CrtYd" user "Package Geometry/Place Bound Top")
		(29 "B.CrtYd" user "Package Geometry/Place Bound Bottom")
		(35 "F.Fab" user "Ref Des/Assembly Top")
		(33 "B.Fab" user "Ref Des/Assembly Bottom")
	)
	(footprint ""
		(layer "F.Cu")
		(at 270.000222 -76.550012 180)
		(property "Reference" "U5D1"
			(at 19.124422 31.601918 0)
			(unlocked yes)
			(layer "F.SilkS")
			(effects
				(font
					(size 0.7874 0.5842)
					(thickness 0.1524)
				)
			)
		)
		(property "Value" ""
			(at 0 0 180)
			(layer "F.Fab")
			(effects
				(font
					(size 1.27 1.27)
				)
			)
		)
		(duplicate_pad_numbers_are_jumpers no)
		(pad "EE48" smd circle
			(at 4.627626 24.608028)
			(size 0.4318 0.4318)
			(layers "F.Cu" "F.Mask" "F.Paste")
			(net "M_D_ODT<1>")
		)
		(pad "EE50" smd circle
			(at 6.344412 24.608028)
			(size 0.4318 0.4318)
			(layers "F.Cu" "F.Mask" "F.Paste")
			(net "M_D_ODT<0>")
		)
		(pad "EE52" smd circle
			(at 8.061452 24.608028)
			(size 0.4318 0.4318)
			(layers "F.Cu" "F.Mask" "F.Paste")
			(net "M_D_BA<0>")
		)
		(pad "EE54" smd circle
			(at 9.778492 24.608028)
			(size 0.4318 0.4318)
			(layers "F.Cu" "F.Mask" "F.Paste")
			(net "M_D_CLK_DP<1>")
		)
		(pad "EE56" smd circle
			(at 11.495532 24.608028)
			(size 0.4318 0.4318)
			(layers "F.Cu" "F.Mask" "F.Paste")
			(net "M_D_CLK_DP<3>")
		)
		(pad "EE58" smd circle
			(at 13.212572 24.608028)
			(size 0.4318 0.4318)
			(layers "F.Cu" "F.Mask" "F.Paste")
			(net "M_D_MA<2>")
		)
		(pad "EE60" smd circle
			(at 14.929612 24.608028)
			(size 0.4318 0.4318)
			(layers "F.Cu" "F.Mask" "F.Paste")
			(net "M_D_MA<6>")
		)
		(pad "EE62" smd circle
			(at 16.646398 24.608028)
			(size 0.4318 0.4318)
			(layers "F.Cu" "F.Mask" "F.Paste")
			(net "M_D_CKE<0>")
		)
		(pad "EE70" smd custom
			(at 23.514558 24.608028 180)
			(size 0.10795 0.10795)
			(layers "F.Cu" "F.Mask" "F.Paste")
			(net "GND")
			(options
				(clearance outline)
				(anchor circle)
			)
			(primitives
				(gr_poly
					(pts
						(arc
							(start 0.2159 -0.0381)
							(mid 0 -0.254)
							(end -0.2159 -0.0381)
						)
						(arc
							(start -0.2159 0.0381)
							(mid 0 0.254)
							(end 0.2159 0.0381)
						)
					)
					(width 0)
					(fill yes)
				)
			)
		)
		(pad "EE72" smd circle
			(at 25.231598 24.608028)
			(size 0.4318 0.4318)
			(layers "F.Cu" "F.Mask" "F.Paste")
			(net "M_E_DQ<31>")
		)
		(pad "EE74" smd circle
			(at 26.948384 24.608028)
			(size 0.4318 0.4318)
			(layers "F.Cu" "F.Mask" "F.Paste")
			(net "M_E_DQ<25>")
		)
		(pad "EE76" smd circle
			(at 28.665424 24.608028)
			(size 0.4318 0.4318)
			(layers "F.Cu" "F.Mask" "F.Paste")
			(net "GND")
		)
		(pad "EE78" smd circle
			(at 30.382464 24.608028)
			(size 0.4318 0.4318)
			(layers "F.Cu" "F.Mask" "F.Paste")
			(net "GND")
		)
		(pad "EE80" smd custom
			(at 32.099504 24.608028 225)
			(size 0.10795 0.10795)
			(layers "F.Cu" "F.Mask" "F.Paste")
			(net "GND")
			(options
				(clearance outline)
				(anchor circle)
			)
			(primitives
				(gr_poly
					(pts
						(arc
							(start 0.2159 -0.0381)
							(mid 0 -0.254)
							(end -0.2159 -0.0381)
						)
						(arc
							(start -0.2159 0.0381)
							(mid 0 0.254)
							(end 0.2159 0.0381)
						)
					)
					(width 0)
					(fill yes)
				)
			)
		)
		(pad "EE82" smd custom
			(at 33.816544 24.608028 270)
			(size 0.10795 0.10795)
			(layers "F.Cu" "F.Mask" "F.Paste")
			(net "TP_CPU0_RSVD_5")
			(options
				(clearance outline)
				(anchor circle)
			)
			(primitives
				(gr_poly
					(pts
						(arc
							(start 0.2159 -0.0381)
							(mid 0 -0.254)
							(end -0.2159 -0.0381)
						)
						(arc
							(start -0.2159 0.0381)
							(mid 0 0.254)
							(end 0.2159 0.0381)
						)
					)
					(width 0)
					(fill yes)
				)
			)
		)
		(pad "EE84" smd custom
			(at 35.533584 24.608028 270)
			(size 0.10795 0.10795)
			(layers "F.Cu" "F.Mask" "F.Paste")
			(net "TP_CPU0_RSVD_4")
			(options
				(clearance outline)
				(anchor circle)
			)
			(primitives
				(gr_poly
					(pts
						(arc
							(start 0.2159 -0.0381)
							(mid 0 -0.254)
							(end -0.2159 -0.0381)
						)
						(arc
							(start -0.2159 0.0381)
							(mid 0 0.254)
							(end 0.2159 0.0381)
						)
					)
					(width 0)
					(fill yes)
				)
			)
		)
		(pad "EF45" smd custom
			(at 2.052066 25.103074 135)
			(size 0.10795 0.10795)
			(layers "F.Cu" "F.Mask" "F.Paste")
			(net "PVDDQ_DEF")
			(options
				(clearance outline)
				(anchor circle)
			)
			(primitives
				(gr_poly
					(pts
						(arc
							(start 0.2159 -0.0381)
							(mid 0 -0.254)
							(end -0.2159 -0.0381)
						)
						(arc
							(start -0.2159 0.0381)
							(mid 0 0.254)
							(end 0.2159 0.0381)
						)
					)
					(width 0)
					(fill yes)
				)
			)
		)
		(pad "EF47" smd custom
			(at 3.769106 25.103074 180)
			(size 0.10795 0.10795)
			(layers "F.Cu" "F.Mask" "F.Paste")
			(net "TP_CPU0_RSVD_3")
			(options
				(clearance outline)
				(anchor circle)
			)
			(primitives
				(gr_poly
					(pts
						(arc
							(start 0.2159 -0.0381)
							(mid 0 -0.254)
							(end -0.2159 -0.0381)
						)
						(arc
							(start -0.2159 0.0381)
							(mid 0 0.254)
							(end 0.2159 0.0381)
						)
					)
					(width 0)
					(fill yes)
				)
			)
		)
		(pad "EF49" smd custom
			(at 5.485892 25.103074 180)
			(size 0.10795 0.10795)
			(layers "F.Cu" "F.Mask" "F.Paste")
			(net "PVDDQ_DEF")
			(options
				(clearance outline)
				(anchor circle)
			)
			(primitives
				(gr_poly
					(pts
						(arc
							(start 0.2159 -0.0381)
							(mid 0 -0.254)
							(end -0.2159 -0.0381)
						)
						(arc
							(start -0.2159 0.0381)
							(mid 0 0.254)
							(end 0.2159 0.0381)
						)
					)
					(width 0)
					(fill yes)
				)
			)
		)
		(pad "EF51" smd custom
			(at 7.202932 25.103074 180)
			(size 0.10795 0.10795)
			(layers "F.Cu" "F.Mask" "F.Paste")
			(net "M_D_CS_N<0>")
			(options
				(clearance outline)
				(anchor circle)
			)
			(primitives
				(gr_poly
					(pts
						(arc
							(start 0.2159 -0.0381)
							(mid 0 -0.254)
							(end -0.2159 -0.0381)
						)
						(arc
							(start -0.2159 0.0381)
							(mid 0 0.254)
							(end 0.2159 0.0381)
						)
					)
					(width 0)
					(fill yes)
				)
			)
		)
		(pad "EF53" smd custom
			(at 8.919972 25.103074 180)
			(size 0.10795 0.10795)
			(layers "F.Cu" "F.Mask" "F.Paste")
			(net "PVDDQ_DEF")
			(options
				(clearance outline)
				(anchor circle)
			)
			(primitives
				(gr_poly
					(pts
						(arc
							(start 0.2159 -0.0381)
							(mid 0 -0.254)
							(end -0.2159 -0.0381)
						)
						(arc
							(start -0.2159 0.0381)
							(mid 0 0.254)
							(end 0.2159 0.0381)
						)
					)
					(width 0)
					(fill yes)
				)
			)
		)
		(pad "EF55" smd custom
			(at 10.637012 25.103074 180)
			(size 0.10795 0.10795)
			(layers "F.Cu" "F.Mask" "F.Paste")
			(net "M_D_CLK_DN<1>")
			(options
				(clearance outline)
				(anchor circle)
			)
			(primitives
				(gr_poly
					(pts
						(arc
							(start 0.2159 -0.0381)
							(mid 0 -0.254)
							(end -0.2159 -0.0381)
						)
						(arc
							(start -0.2159 0.0381)
							(mid 0 0.254)
							(end 0.2159 0.0381)
						)
					)
					(width 0)
					(fill yes)
				)
			)
		)
		(pad "EF57" smd custom
			(at 12.354052 25.103074 180)
			(size 0.10795 0.10795)
			(layers "F.Cu" "F.Mask" "F.Paste")
			(net "M_D_CLK_DN<3>")
			(options
				(clearance outline)
				(anchor circle)
			)
			(primitives
				(gr_poly
					(pts
						(arc
							(start 0.2159 -0.0381)
							(mid 0 -0.254)
							(end -0.2159 -0.0381)
						)
						(arc
							(start -0.2159 0.0381)
							(mid 0 0.254)
							(end 0.2159 0.0381)
						)
					)
					(width 0)
					(fill yes)
				)
			)
		)
		(pad "EF59" smd custom
			(at 14.071092 25.103074 180)
			(size 0.10795 0.10795)
			(layers "F.Cu" "F.Mask" "F.Paste")
			(net "PVDDQ_DEF")
			(options
				(clearance outline)
				(anchor circle)
			)
			(primitives
				(gr_poly
					(pts
						(arc
							(start 0.2159 -0.0381)
							(mid 0 -0.254)
							(end -0.2159 -0.0381)
						)
						(arc
							(start -0.2159 0.0381)
							(mid 0 0.254)
							(end 0.2159 0.0381)
						)
					)
					(width 0)
					(fill yes)
				)
			)
		)
		(pad "EF61" smd custom
			(at 15.787878 25.103074 180)
			(size 0.10795 0.10795)
			(layers "F.Cu" "F.Mask" "F.Paste")
			(net "M_D_MA<9>")
			(options
				(clearance outline)
				(anchor circle)
			)
			(primitives
				(gr_poly
					(pts
						(arc
							(start 0.2159 -0.0381)
							(mid 0 -0.254)
							(end -0.2159 -0.0381)
						)
						(arc
							(start -0.2159 0.0381)
							(mid 0 0.254)
							(end 0.2159 0.0381)
						)
					)
					(width 0)
					(fill yes)
				)
			)
		)
		(pad "EF63" smd custom
			(at 17.504918 25.103074 180)
			(size 0.10795 0.10795)
			(layers "F.Cu" "F.Mask" "F.Paste")
			(net "M_D_CKE<1>")
			(options
				(clearance outline)
				(anchor circle)
			)
			(primitives
				(gr_poly
					(pts
						(arc
							(start 0.2159 -0.0381)
							(mid 0 -0.254)
							(end -0.2159 -0.0381)
						)
						(arc
							(start -0.2159 0.0381)
							(mid 0 0.254)
							(end 0.2159 0.0381)
						)
					)
					(width 0)
					(fill yes)
				)
			)
		)
		(pad "EF71" smd custom
			(at 24.373078 25.103074 180)
			(size 0.10795 0.10795)
			(layers "F.Cu" "F.Mask" "F.Paste")
			(net "GND")
			(options
				(clearance outline)
				(anchor circle)
			)
			(primitives
				(gr_poly
					(pts
						(arc
							(start 0.2159 -0.0381)
							(mid 0 -0.254)
							(end -0.2159 -0.0381)
						)
						(arc
							(start -0.2159 0.0381)
							(mid 0 0.254)
							(end 0.2159 0.0381)
						)
					)
					(width 0)
					(fill yes)
				)
			)
		)
		(pad "EF73" smd custom
			(at 26.090118 25.103074 180)
			(size 0.10795 0.10795)
			(layers "F.Cu" "F.Mask" "F.Paste")
			(net "M_E_DQS_DN<3>")
			(options
				(clearance outline)
				(anchor circle)
			)
			(primitives
				(gr_poly
					(pts
						(arc
							(start 0.2159 -0.0381)
							(mid 0 -0.254)
							(end -0.2159 -0.0381)
						)
						(arc
							(start -0.2159 0.0381)
							(mid 0 0.254)
							(end 0.2159 0.0381)
						)
					)
					(width 0)
					(fill yes)
				)
			)
		)
		(pad "EF75" smd custom
			(at 27.806904 25.103074 180)
			(size 0.10795 0.10795)
			(layers "F.Cu" "F.Mask" "F.Paste")
			(net "GND")
			(options
				(clearance outline)
				(anchor circle)
			)
			(primitives
				(gr_poly
					(pts
						(arc
							(start 0.2159 -0.0381)
							(mid 0 -0.254)
							(end -0.2159 -0.0381)
						)
						(arc
							(start -0.2159 0.0381)
							(mid 0 0.254)
							(end 0.2159 0.0381)
						)
					)
					(width 0)
					(fill yes)
				)
			)
		)
		(pad "EF77" smd custom
			(at 29.523944 25.103074 180)
			(size 0.10795 0.10795)
			(layers "F.Cu" "F.Mask" "F.Paste")
			(net "TP_CPU0_RSVD_2")
			(options
				(clearance outline)
				(anchor circle)
			)
			(primitives
				(gr_poly
					(pts
						(arc
							(start 0.2159 -0.0381)
							(mid 0 -0.254)
							(end -0.2159 -0.0381)
						)
						(arc
							(start -0.2159 0.0381)
							(mid 0 0.254)
							(end 0.2159 0.0381)
						)
					)
					(width 0)
					(fill yes)
				)
			)
		)
		(pad "EF79" smd custom
			(at 31.240984 25.103074 180)
			(size 0.10795 0.10795)
			(layers "F.Cu" "F.Mask" "F.Paste")
			(net "GND")
			(options
				(clearance outline)
				(anchor circle)
			)
			(primitives
				(gr_poly
					(pts
						(arc
							(start 0.2159 -0.0381)
							(mid 0 -0.254)
							(end -0.2159 -0.0381)
						)
						(arc
							(start -0.2159 0.0381)
							(mid 0 0.254)
							(end 0.2159 0.0381)
						)
					)
					(width 0)
					(fill yes)
				)
			)
		)
		(pad "EF81" smd custom
			(at 32.958024 25.103074 225)
			(size 0.10795 0.10795)
			(layers "F.Cu" "F.Mask" "F.Paste")
			(net "TP_CPU0_RSVD_1")
			(options
				(clearance outline)
				(anchor circle)
			)
			(primitives
				(gr_poly
					(pts
						(arc
							(start 0.2159 -0.0381)
							(mid 0 -0.254)
							(end -0.2159 -0.0381)
						)
						(arc
							(start -0.2159 0.0381)
							(mid 0 0.254)
							(end 0.2159 0.0381)
						)
					)
					(width 0)
					(fill yes)
				)
			)
		)
		(pad "EF83" smd custom
			(at 34.675064 25.103074 225)
			(size 0.10795 0.10795)
			(layers "F.Cu" "F.Mask" "F.Paste")
			(net "TP_CPU0_RSVD_0")
			(options
				(clearance outline)
				(anchor circle)
			)
			(primitives
				(gr_poly
					(pts
						(arc
							(start 0.2159 -0.0381)
							(mid 0 -0.254)
							(end -0.2159 -0.0381)
						)
						(arc
							(start -0.2159 0.0381)
							(mid 0 0.254)
							(end 0.2159 0.0381)
						)
					)
					(width 0)
					(fill yes)
				)
			)
		)
		(pad "F3" smd custom
			(at -35.533584 -22.626828 45)
			(size 0.10795 0.10795)
			(layers "F.Cu" "F.Mask" "F.Paste")
			(net "TP_CPU0_RSVD_279")
			(options
				(clearance outline)
				(anchor circle)
			)
			(primitives
				(gr_poly
					(pts
						(arc
							(start 0.2159 -0.0381)
							(mid 0 -0.254)
							(end -0.2159 -0.0381)
						)
						(arc
							(start -0.2159 0.0381)
							(mid 0 0.254)
							(end 0.2159 0.0381)
						)
					)
					(width 0)
					(fill yes)
				)
			)
		)
		(pad "F5" smd circle
			(at -33.816544 -22.626828)
			(size 0.4318 0.4318)
			(layers "F.Cu" "F.Mask" "F.Paste")
			(net "GND")
		)
		(pad "F7" smd circle
			(at -32.099504 -22.626828)
			(size 0.4318 0.4318)
			(layers "F.Cu" "F.Mask" "F.Paste")
			(net "UPI_CPU0_CPU1_P1P1_DP<15>")
		)
		(pad "F9" smd circle
			(at -30.382464 -22.626828)
			(size 0.4318 0.4318)
			(layers "F.Cu" "F.Mask" "F.Paste")
			(net "UPI_CPU0_CPU1_P1P1_DP<12>")
		)
		(pad "F11" smd circle
			(at -28.665424 -22.626828)
			(size 0.4318 0.4318)
			(layers "F.Cu" "F.Mask" "F.Paste")
			(net "UPI_CPU0_CPU1_P1P1_DN<11>")
		)
		(pad "F13" smd circle
			(at -26.948384 -22.626828)
			(size 0.4318 0.4318)
			(layers "F.Cu" "F.Mask" "F.Paste")
			(net "UPI_CPU0_CPU1_P1P1_DP<8>")
		)
		(pad "F15" smd circle
			(at -25.231598 -22.626828)
			(size 0.4318 0.4318)
			(layers "F.Cu" "F.Mask" "F.Paste")
			(net "UPI_CPU0_CPU1_P1P1_DN<6>")
		)
		(pad "F17" smd circle
			(at -23.514558 -22.626828)
			(size 0.4318 0.4318)
			(layers "F.Cu" "F.Mask" "F.Paste")
			(net "GND")
		)
		(pad "F19" smd circle
			(at -21.797518 -22.626828)
			(size 0.4318 0.4318)
			(layers "F.Cu" "F.Mask" "F.Paste")
			(net "GND")
		)
		(pad "F21" smd circle
			(at -20.080478 -22.626828)
			(size 0.4318 0.4318)
			(layers "F.Cu" "F.Mask" "F.Paste")
			(net "UPI_CPU0_CPU1_P1P1_DN<1>")
		)
		(pad "F23" smd circle
			(at -18.363438 -22.626828)
			(size 0.4318 0.4318)
			(layers "F.Cu" "F.Mask" "F.Paste")
			(net "TP_CPU0_RSVD_278")
		)
		(pad "F25" smd circle
			(at -16.646398 -22.626828)
			(size 0.4318 0.4318)
			(layers "F.Cu" "F.Mask" "F.Paste")
			(net "GND")
		)
		(pad "F27" smd circle
			(at -14.929612 -22.626828)
			(size 0.4318 0.4318)
			(layers "F.Cu" "F.Mask" "F.Paste")
			(net "M_B_DQ<55>")
		)
		(pad "F29" smd circle
			(at -13.212572 -22.626828)
			(size 0.4318 0.4318)
			(layers "F.Cu" "F.Mask" "F.Paste")
			(net "M_B_DQ<53>")
		)
		(pad "F31" smd circle
			(at -11.495532 -22.626828)
			(size 0.4318 0.4318)
			(layers "F.Cu" "F.Mask" "F.Paste")
			(net "GND")
		)
		(pad "F33" smd circle
			(at -9.778492 -22.626828)
			(size 0.4318 0.4318)
			(layers "F.Cu" "F.Mask" "F.Paste")
			(net "M_B_DQ<47>")
		)
		(pad "F35" smd circle
			(at -8.061452 -22.626828)
			(size 0.4318 0.4318)
			(layers "F.Cu" "F.Mask" "F.Paste")
			(net "M_B_DQ<45>")
		)
		(pad "F37" smd circle
			(at -6.344412 -22.626828)
			(size 0.4318 0.4318)
			(layers "F.Cu" "F.Mask" "F.Paste")
			(net "GND")
		)
		(pad "F39" smd circle
			(at -4.627626 -22.626828)
			(size 0.4318 0.4318)
			(layers "F.Cu" "F.Mask" "F.Paste")
			(net "M_A_DQ<39>")
		)
		(pad "F41" smd circle
			(at -2.910586 -22.626828)
			(size 0.4318 0.4318)
			(layers "F.Cu" "F.Mask" "F.Paste")
			(net "M_A_DQ<37>")
		)
		(pad "F43" smd circle
			(at -1.193546 -22.626828)
			(size 0.4318 0.4318)
			(layers "F.Cu" "F.Mask" "F.Paste")
			(net "GND")
		)
		(pad "F45" smd circle
			(at 2.052066 -24.426672)
			(size 0.508 0.508)
			(layers "F.Cu" "F.Mask" "F.Paste")
			(net "M_A_CS_N<6>")
		)
		(pad "F47" smd circle
			(at 3.769106 -24.426672)
			(size 0.4318 0.4318)
			(layers "F.Cu" "F.Mask" "F.Paste")
			(net "M_A_CS_N<3>")
		)
		(pad "F49" smd circle
			(at 5.485892 -24.426672)
			(size 0.4318 0.4318)
			(layers "F.Cu" "F.Mask" "F.Paste")
			(net "M_A_CS_N<1>")
		)
		(pad "F51" smd circle
			(at 7.202932 -24.426672)
			(size 0.4318 0.4318)
			(layers "F.Cu" "F.Mask" "F.Paste")
			(net "M_A_MA<14>")
		)
		(pad "F53" smd circle
			(at 8.919972 -24.426672)
			(size 0.4318 0.4318)
			(layers "F.Cu" "F.Mask" "F.Paste")
			(net "M_A_MA<0>")
		)
		(pad "F55" smd circle
			(at 10.637012 -24.426672)
			(size 0.4318 0.4318)
			(layers "F.Cu" "F.Mask" "F.Paste")
			(net "M_A_CLK_DN<0>")
		)
		(pad "F57" smd circle
			(at 12.354052 -24.426672)
			(size 0.4318 0.4318)
			(layers "F.Cu" "F.Mask" "F.Paste")
			(net "M_A_MA<1>")
		)
		(pad "F59" smd circle
			(at 14.071092 -24.426672)
			(size 0.4318 0.4318)
			(layers "F.Cu" "F.Mask" "F.Paste")
			(net "M_A_MA<5>")
		)
		(pad "F61" smd circle
			(at 15.787878 -24.426672)
			(size 0.4318 0.4318)
			(layers "F.Cu" "F.Mask" "F.Paste")
			(net "M_A_MA<9>")
		)
		(pad "F63" smd circle
			(at 17.504918 -24.426672)
			(size 0.4318 0.4318)
			(layers "F.Cu" "F.Mask" "F.Paste")
			(net "M_A_BG<1>")
		)
		(pad "F65" smd circle
			(at 19.221958 -24.426672)
			(size 0.4318 0.4318)
			(layers "F.Cu" "F.Mask" "F.Paste")
			(net "TP_CPU0_RSVD_277")
		)
		(pad "F67" smd custom
			(at 20.938998 -24.426672)
			(size 0.10795 0.10795)
			(layers "F.Cu" "F.Mask" "F.Paste")
			(net "GND")
			(options
				(clearance outline)
				(anchor circle)
			)
			(primitives
				(gr_poly
					(pts
						(arc
							(start 0.2159 -0.0381)
							(mid 0 -0.254)
							(end -0.2159 -0.0381)
						)
						(arc
							(start -0.2159 0.0381)
							(mid 0 0.254)
							(end 0.2159 0.0381)
						)
					)
					(width 0)
					(fill yes)
				)
			)
		)
		(pad "F69" smd custom
			(at 22.656038 -24.426672)
			(size 0.10795 0.10795)
			(layers "F.Cu" "F.Mask" "F.Paste")
			(net "GND")
			(options
				(clearance outline)
				(anchor circle)
			)
			(primitives
				(gr_poly
					(pts
						(arc
							(start 0.2159 -0.0381)
							(mid 0 -0.254)
							(end -0.2159 -0.0381)
						)
						(arc
							(start -0.2159 0.0381)
							(mid 0 0.254)
							(end 0.2159 0.0381)
						)
					)
					(width 0)
					(fill yes)
				)
			)
		)
	)
)
